#ISCELL
  mstr_misc dns *
  *
#ISCELL
  pure_quanta quanta_title_block_c *
  *
#ISCELL
  pure_quanta_power universal_gnd *
  page171_i1
#CELL
  pure_quanta q_res *
  page171_i11
#ISCELL
  pure_quanta_power universal_gnd *
  page171_i15
#CELL
  pure_quanta q_res *
  page171_i17
#CELL
  pure_quanta q_res *
  page171_i18
#CELL
  pure_quanta q_cap *
  page171_i19
#CELL
  pure_quanta q_cap *
  page171_i2
#CELL
  pure_quanta q_cap *
  page171_i20
#CELL
  pure_quanta q_cap *
  page171_i21
#CELL
  pure_quanta q_cap *
  page171_i22
#CELL
  pure_quanta q_inductor4p_14 *
  page171_i23
#ISCELL
  pure_quanta_power universal_gnd *
  page171_i24
#CELL
  pure_quanta q_cap *
  page171_i25
#ISCELL
  pure_quanta_power vcc_core *
  page171_i26
#ISCELL
  standard offpage *
  page171_i27
#ISCELL
  standard offpage *
  page171_i3
#CELL
  pure_quanta q_cap *
  page171_i30
#ISCELL
  pure_quanta_power universal_gnd *
  page171_i31
#CELL
  pure_quanta q_cap *
  page171_i32
#ISCELL
  pure_quanta_power vcc_core *
  page171_i33
#ISCELL
  standard offpage *
  page171_i34
#CELL
  pure_quanta q_cap *
  page171_i36
#CELL
  pure_quanta q_cap *
  page171_i37
#ISCELL
  pure_quanta_power universal_gnd *
  page171_i38
#ISCELL
  pure_quanta_power universal_gnd *
  page171_i39
#ISCELL
  standard offpage *
  page171_i4
#CELL
  pure_quanta q_res *
  page171_i40
#CELL
  pure_quanta q_cap *
  page171_i41
#CELL
  pure_quanta isl99390frztr5935 *
  page171_i43
#CELL
  pure_quanta isl99390frztr5935 *
  page171_i44
#ISCELL
  pure_quanta_power vcc_core *
  page171_i45
#CELL
  pure_quanta q_cap *
  page171_i46
#ISCELL
  pure_quanta_power universal_gnd *
  page171_i47
#CELL
  pure_quanta q_cap *
  page171_i48
#ISCELL
  standard offpage *
  page171_i49
#ISCELL
  pure_quanta_power universal_gnd *
  page171_i5
#ISCELL
  pure_quanta_power vcc_core *
  page171_i50
#CELL
  pure_quanta q_cap *
  page171_i51
#ISCELL
  pure_quanta_power universal_gnd *
  page171_i52
#CELL
  pure_quanta q_inductor4p_14 *
  page171_i53
#CELL
  pure_quanta q_cap *
  page171_i54
#CELL
  pure_quanta q_cap *
  page171_i56
#CELL
  pure_quanta q_cap *
  page171_i57
#CELL
  pure_quanta q_cap *
  page171_i58
#CELL
  pure_quanta q_res *
  page171_i59
#ISCELL
  standard offpage *
  page171_i6
#CELL
  pure_quanta q_res *
  page171_i60
#CELL
  pure_quanta q_cap *
  page171_i61
#CELL
  pure_quanta q_cap *
  page171_i63
#ISCELL
  pure_quanta_power universal_gnd *
  page171_i64
#CELL
  pure_quanta q_res *
  page171_i65
#ISCELL
  standard offpage *
  page171_i66
#CELL
  pure_quanta q_cap *
  page171_i67
#ISCELL
  pure_quanta_power universal_gnd *
  page171_i68
#CELL
  pure_quanta q_res *
  page171_i69
#ISCELL
  standard offpage *
  page171_i70
#ISCELL
  pure_quanta_power universal_gnd *
  page171_i71
#CELL
  pure_quanta q_cap *
  page171_i72
#ISCELL
  pure_quanta_power universal_gnd *
  page171_i73
#ISCELL
  standard offpage *
  page171_i74
#ISCELL
  pure_quanta_power universal_gnd *
  page171_i75
#ISCELL
  standard offpage *
  page171_i76
#CELL
  pure_quanta q_cap *
  page171_i77
#CELL
  pure_quanta q_res *
  page171_i78
#ISCELL
  pure_quanta_power universal_gnd *
  page171_i79
#ISCELL
  standard offpage *
  page171_i8
#CELL
  pure_quanta q_cap *
  page171_i80
#CELL
  pure_quanta q_res *
  page171_i81
#ISCELL
  pure_quanta_power universal_gnd *
  page171_i82
#ISCELL
  pure_quanta_power vcc_core *
  page171_i83
#ISCELL
  pure_quanta_power vcc_core *
  page171_i84
#ISCELL
  pure_quanta_power universal_gnd *
  page171_i85
#CELL
  pure_quanta q_inductor *
  page171_i86
